FILE_TYPE = CONNECTIVITY;
{Allegro Design Entry HDL 16.6-p007 (v16-6-112F) 10/10/2012}
"PAGE_NUMBER" = 221;
0"NC";
1"PVTT_ABC\g";
2"GND\g";
3"GND\g";
4"GND\g";
5"GND\g";
6"GND\g";
7"PVDDQ_ABC\g";
8"GND\g";
9"GND\g";
10"GND\g";
11"P3V3\g";
12"P3V3\g";
13"GND\g";
14"PVTT_ABC\g";
15"GND\g";
16"PWRGD_PVTT_CPU0";
17"PWRGD_PVTT_ABC_CPU0_R";
18"VR_PVTT_ABC_VREF";
19"VR_PVTT_ABC_BIAS";
20"VR_PVTT_ABC_SNS";
21"VSENSE_PVDDQ_ABC_VTT";
22"FM_PVTT_ABC_EN_R";
23"PWRGD_PVDDQ_ABC";
%"MIC5166"
"1","(1550,1050)","0","mstr_vreg","I1";
;
CDS_SEC"1"
CDS_LIB"mstr_vreg"
CDS_LMAN_SYM_OUTLINE"-250,350,250,-350"
BOM_COST"MEM_VRD_VTT_ABC"
PACK_TYPE"DFN"
ROOM"VTT_ABC_PWR_VR"
SEC"1"
SEC_TYPE"DFN"
CDS_LOCATION"EU4G3"
LOCATION"EU4G3"
MATERIAL"IC"
PART_NUMBER"H55101-001";
"THPAD"
$PN"11"8;
"VTT"
$PN"9"14;
"PGND"
$PN"8"8;
"SNS"
$PN"6"20;
"VDDQ"
$PN"4"21;
"PG"
$PN"5"17;
"AGND"
$PN"3"8;
"BIAS"
$PN"2"19;
"VREF"
$PN"1"18;
"VIN"
$PN"10"7;
"EN"
$PN"7"22;
%"PVTT_ABC"
"1","(3600,3725)","0","mstr_symbols","I11";
;
ROOM"VTT_ABC_PWR_VR"
BOM_COST"MEM_VRD_PVDDQ_AB"
CDS_LIB"mstr_symbols"
HDL_POWER"PVTT_ABC"
VOLTAGE"0.6V"
BODY_TYPE"PLUMBING";
"G\NAC"1;
%"GND"
"1","(3875,1375)","0","mstr_symbols","I14";
;
HDL_POWER"GND"
SIZE"1B"
CDS_LIB"mstr_symbols"
VOLTAGE"0.0V"
BODY_TYPE"PLUMBING";
"A\NAC"2;
%"CAP"
"1","(3875,1600)","0","mstr_discrete","I15";
;
CDS_SEC"1"
SEC"1"
SEC_TYPE"0402LF"
BOM_COST"MEM_VRD_VTT_ABC"
ROOM"VTT_ABC_PWR_VR"
CDS_LOCATION"C4G14"
CDS_LIB"mstr_discrete"
PART_NUMBER"A36096-046"
VALUE"1000PF"
PACK_TYPE"0402LF"
LOCATION"C4G14"
TOLERANCE"10%"
VOLTAGE"50V"
MATERIAL"X7R";
"A"
$PN"1"17;
"B"
$PN"2"2;
%"GND"
"1","(3975,600)","0","mstr_symbols","I19";
;
HDL_POWER"GND"
VOLTAGE"0.0V"
BODY_TYPE"PLUMBING"
SIZE"1B"
CDS_LIB"mstr_symbols";
"A\NAC"3;
%"CAP"
"1","(3975,1025)","0","mstr_discrete","I20";
;
CDS_SEC"1"
SEC_TYPE"0805LF"
ROOM"VTT_ABC_PWR_VR"
CDS_LOCATION"C4G24"
SEC"1"
CDS_LIB"mstr_discrete"
BOM_COST"MEM_VRD_VTT_ABC"
LOCATION"C4G24"
VALUE"22UF"
TOLERANCE"20%"
PACK_TYPE"0805LF"
MATERIAL"X6S"
VOLTAGE"4V"
PART_NUMBER"C95333-002";
"A"
$PN"1"14;
"B"
$PN"2"3;
%"CAP"
"1","(475,2350)","0","mstr_discrete","I22";
;
CDS_SEC"1"
SEC_TYPE"0603LF"
SEC"1"
BOM_COST"MEM_VRD_VTT_ABC"
CDS_LOCATION"C6U16"
ROOM"VTT_ABC_PWR_VR"
CDS_LIB"mstr_discrete"
MATERIAL"X6S"
VOLTAGE"4V"
PACK_TYPE"0603LF"
TOLERANCE"20%"
VALUE"10UF"
PART_NUMBER"E15431-001"
LOCATION"C6U16";
"A"
$PN"1"7;
"B"
$PN"2"4;
%"GND"
"1","(475,2100)","0","mstr_symbols","I23";
;
SIZE"1B"
VOLTAGE"0.0V"
HDL_POWER"GND"
BODY_TYPE"PLUMBING"
CDS_LIB"mstr_symbols"
ROOM"VTT_ABC_PWR_VR"
BOM_COST"MEM_VRD_VTT_ABC";
"A\NAC"4;
%"CAP"
"1","(475,1475)","0","mstr_discrete","I24";
;
BOM_COST"MEM_VRD_VTT_ABC"
CDS_SEC"1"
$SEC"1"
CDS_LOCATION"C4G15"
ROOM"VTT_ABC_PWR_VR"
CDS_LIB"mstr_discrete"
LOCATION"C4G15"
VOLTAGE"16V"
VALUE"1.0UF"
MATERIAL"X6S"
PACK_TYPE"0402"
TOLERANCE"10%"
PART_NUMBER"D97712-011";
"A"
$PN"1"19;
"B"
$PN"2"5;
%"GND"
"1","(475,1250)","0","mstr_symbols","I25";
;
SIZE"1B"
HDL_POWER"GND"
CDS_LIB"mstr_symbols"
BODY_TYPE"PLUMBING"
VOLTAGE"0.0V";
"A\NAC"5;
%"CAP"
"1","(50,2325)","0","mstr_discrete","I26";
;
CDS_SEC"1"
SEC"1"
SEC_TYPE"0603LF"
BOM_COST"MEM_VRD_VTT_ABC"
ROOM"VTT_ABC_PWR_VR"
CDS_LOCATION"C6U15"
CDS_LIB"mstr_discrete"
PART_NUMBER"E15431-001"
PACK_TYPE"0603LF"
VOLTAGE"4V"
VALUE"10UF"
LOCATION"C6U15"
TOLERANCE"20%"
MATERIAL"X6S";
"A"
$PN"1"7;
"B"
$PN"2"6;
%"RES"
"1","(125,1750)","0","mstr_discrete","I28";
;
CDS_SEC"1"
ROOM"VTT_ABC_PWR_VR"
SEC"1"
CDS_LOCATION"R6U4"
SEC_TYPE"0402"
BOM_COST"MEM_VRD_VTT_ABC"
CDS_LIB"mstr_discrete"
LOCATION"R6U4"
PACK_TYPE"0402"
MATERIAL"CHIP"
TOLERANCE"5%"
VALUE"0.0"
PART_NUMBER"G21497-005"
WATTAGE"1/16W";
"B"
$PN"2"19;
"A"
$PN"1"11;
%"GND"
"1","(50,2100)","0","mstr_symbols","I29";
;
HDL_POWER"GND"
VOLTAGE"0.0V"
BODY_TYPE"PLUMBING"
CDS_LIB"mstr_symbols"
SIZE"1B"
ROOM"VTT_ABC_PWR_VR"
BOM_COST"MEM_VRD_VTT_ABC";
"A\NAC"6;
%"PVDDQ_ABC"
"1","(-1425,2775)","0","mstr_symbols","I31";
;
CDS_LIB"mstr_symbols"
BODY_TYPE"PLUMBING"
HDL_POWER"PVDDQ_ABC"
VOLTAGE"1.2V";
"G\NAC"7;
%"RES"
"2","(-775,1525)","1","mstr_discrete","I32";
;
CDS_SEC"1"
SEC_TYPE"0402"
BOM_COST"MEM_VRD_VTT_ABC"
SEC"1"
CDS_LOCATION"R6U5"
NO_XNET_CONNECTION"1"
ROOM"VTT_ABC_PWR_VR"
MATERIAL"CHIP"
CDS_LIB"mstr_discrete"
PACK_TYPE"0402"
LOCATION"R6U5"
PART_NUMBER"G21497-005"
VALUE"0.0"
TOLERANCE"5%"
WATTAGE"1/16W";
"A"
$PN"1"7;
"B"
$PN"2"21;
%"CAP"
"1","(2375,825)","0","mstr_discrete","I34";
;
CDS_SEC"1"
SEC_TYPE"0402"
BOM_COST"MEM_VRD_VTT_ABC"
SEC"1"
ROOM"VTT_ABC_PWR_VR"
CDS_LOCATION"C4G16"
CDS_LIB"mstr_discrete"
VOLTAGE"16V"
LOCATION"C4G16"
PART_NUMBER"D97712-011"
VALUE"1.0UF"
MATERIAL"X6S"
TOLERANCE"10%"
PACK_TYPE"0402";
"A"
$PN"1"18;
"B"
$PN"2"9;
%"GND"
"1","(2000,575)","0","mstr_symbols","I35";
;
SIZE"1B"
HDL_POWER"GND"
VOLTAGE"0.0V"
BODY_TYPE"PLUMBING"
CDS_LIB"mstr_symbols";
"A\NAC"8;
%"GND"
"1","(2375,575)","0","mstr_symbols","I36";
;
SIZE"1B"
HDL_POWER"GND"
VOLTAGE"0.0V"
BODY_TYPE"PLUMBING"
CDS_LIB"mstr_symbols";
"A\NAC"9;
%"RES"
"2","(-325,650)","2","mstr_discrete","I37";
;
CDS_SEC"1"
ROOM"VTT_ABC_PWR_VR"
CDS_LOCATION"R6U15"
SEC"1"
BOM_COST"MEM_VRD_VTT_ABC"
SEC_TYPE"0402"
CDS_LIB"mstr_discrete"
MATERIAL"EMPTY"
VALUE"1.0M"
TOLERANCE"1%"
WATTAGE"1/16W"
PACK_TYPE"0402"
LOCATION"R6U15"
PART_NUMBER"G21796-021";
"A"
$PN"1"11;
"B"
$PN"2"22;
%"RES"
"1","(-525,125)","0","mstr_discrete","I38";
;
CDS_SEC"1"
BOM_COST"MEM_VRD_VTT_ABC"
SEC_TYPE"0402"
SEC"1"
ROOM"VTT_ABC_PWR_VR"
CDS_LIB"mstr_discrete"
CDS_LOCATION"R4G23"
LOCATION"R4G23"
PART_NUMBER"G21497-005"
TOLERANCE"5%"
VALUE"0.0"
WATTAGE"1/16W"
PACK_TYPE"0402"
MATERIAL"CHIP";
"B"
$PN"2"22;
"A"
$PN"1"23;
%"CAP"
"1","(-375,-400)","2","mstr_discrete","I39";
;
CDS_SEC"1"
ROOM"VTT_ABC_PWR_VR"
SEC"1"
SEC_TYPE"0402LF"
BOM_COST"MEM_VRD_VTT_ABC"
CDS_LIB"mstr_discrete"
CDS_LOCATION"C4G23"
PART_NUMBER"A36096-046"
MATERIAL"EMPTY"
LOCATION"C4G23"
VALUE"1000PF"
TOLERANCE"10%"
PACK_TYPE"0402LF"
VOLTAGE"50V";
"A"
$PN"1"22;
"B"
$PN"2"10;
%"GND"
"1","(-375,-625)","0","mstr_symbols","I40";
;
HDL_POWER"GND"
VOLTAGE"0.0V"
BODY_TYPE"PLUMBING"
SIZE"1B"
CDS_LIB"mstr_symbols";
"A\NAC"10;
%"P3V3"
"1","(-550,2050)","0","mstr_symbols","I43";
;
CDS_LIB"mstr_symbols"
SIZE"1B"
BODY_TYPE"PLUMBING"
VOLTAGE"3.3V"
HDL_POWER"P3V3";
"G\NAC"11;
%"RES"
"2","(3500,2025)","0","mstr_discrete","I45";
;
CDS_SEC"1"
BOM_COST"MEM_VRD_VTT_ABC"
SEC_TYPE"0402"
SEC"1"
ROOM"VTT_ABC_PWR_VR"
CDS_LOCATION"R4G18"
CDS_LIB"mstr_discrete"
LOCATION"R4G18"
VALUE"10.0K"
TOLERANCE"1%"
PART_NUMBER"G21796-016"
PACK_TYPE"0402"
MATERIAL"CHIP"
WATTAGE"1/16W";
"A"
$PN"1"12;
"B"
$PN"2"17;
%"P3V3"
"1","(3500,2275)","0","mstr_symbols","I46";
;
CDS_LIB"mstr_symbols"
SIZE"1B"
BODY_TYPE"PLUMBING"
VOLTAGE"3.3V"
HDL_POWER"P3V3";
"G\NAC"12;
%"GND"
"1","(325,775)","0","mstr_symbols","I48";
;
HDL_POWER"GND"
CDS_LIB"mstr_symbols"
VOLTAGE"0.0V"
BODY_TYPE"PLUMBING"
SIZE"1B";
"A\NAC"13;
%"CAP"
"1","(325,1000)","0","mstr_discrete","I49";
;
CDS_SEC"1"
CDS_LOCATION"C6U12"
SEC"1"
SEC_TYPE"0603"
ROOM"VTT_ABC_PWR_VR"
CDS_LIB"mstr_discrete"
LOCATION"C6U12"
VALUE"4.7UF"
VOLTAGE"6.3V"
PART_NUMBER"E15431-003"
MATERIAL"X6S"
PACK_TYPE"0603"
TOLERANCE"10%";
"A"
$PN"1"21;
"B"
$PN"2"13;
%"CAP_A"
"1","(3600,3450)","0","dev_discrete","I50";
;
SEC"1"
SEC_TYPE"0603V"
CDS_SEC"1"
CDS_LOCATION"C5U12"
CDS_LIB"dev_discrete"
PART_NUMBER"602433-106"
MATERIAL"X5R"
VOLTAGE"4V"
TOLERANCE"20%"
VALUE"47UF"
LOCATION"C5U12"
PACK_TYPE"0603V";
"B"
$PN"2"15;
"A"
$PN"1"1;
%"CAP_A"
"1","(3950,3450)","0","dev_discrete","I51";
;
CDS_SEC"1"
SEC_TYPE"0603V"
SEC"1"
CDS_LOCATION"C5T3"
CDS_LIB"dev_discrete"
LOCATION"C5T3"
PART_NUMBER"602433-106"
VALUE"47UF"
PACK_TYPE"0603V"
MATERIAL"X5R"
VOLTAGE"4V"
TOLERANCE"20%";
"B"
$PN"2"15;
"A"
$PN"1"1;
%"CAP_A"
"1","(4350,3450)","0","dev_discrete","I52";
;
SEC"1"
SEC_TYPE"0603V"
CDS_SEC"1"
CDS_LOCATION"C5U16"
CDS_LIB"dev_discrete"
PART_NUMBER"602433-106"
LOCATION"C5U16"
VALUE"47UF"
TOLERANCE"20%"
PACK_TYPE"0603V"
VOLTAGE"4V"
MATERIAL"X5R";
"B"
$PN"2"15;
"A"
$PN"1"1;
%"RES"
"1","(4175,1800)","0","mstr_discrete","I54";
;
CDS_SEC"1"
CDS_LOCATION"R4G19"
SEC_TYPE"0402"
CDS_LIB"mstr_discrete"
SEC"1"
PACK_TYPE"0402"
PART_NUMBER"G21796-074"
LOCATION"R4G19"
MATERIAL"CHIP"
TOLERANCE"1%"
VALUE"33.2"
WATTAGE"1/16W";
"B"
$PN"2"16;
"A"
$PN"1"17;
%"RES"
"1","(4700,1000)","1","mstr_discrete","I55";
;
CDS_SEC"1"
$SEC"1"
CDS_LIB"mstr_discrete"
CDS_LOCATION"R6U16"
PACK_TYPE"0402"
LOCATION"R6U16"
PART_NUMBER"G21796-208"
TOLERANCE"1.0%"
MATERIAL"CHIP"
WATTAGE"1/16W"
VALUE"51.1";
"B"
$PN"2"14;
"A"
$PN"1"3;
%"SHUNT"
"1","(4975,0)","0","mstr_misc","I56";
;
CDS_SEC"1"
CDS_LOCATION"SH5U1"
SEC_TYPE"SH0201"
SEC"1"
CDS_LIB"mstr_misc"
MATERIAL"EMPTY"
PACK_TYPE"SH0201"
PIN_SHORT"A:B"
LOCATION"SH5U1"
PART_NUMBER"N_A";
"A"
$PN"1"20;
"B"
$PN"2"14;
%"PVTT_ABC"
"1","(5525,1575)","0","mstr_symbols","I7";
;
HDL_POWER"PVTT_ABC"
CDS_LIB"mstr_symbols"
VOLTAGE"0.6V"
BODY_TYPE"PLUMBING";
"G\NAC"14;
%"GND"
"1","(4350,3075)","0","mstr_symbols","I8";
;
CDS_LIB"mstr_symbols"
HDL_POWER"GND"
VOLTAGE"0.0V"
BODY_TYPE"PLUMBING"
SIZE"1B"
BOM_COST"MEM_VRD_PVDDQ_AB"
ROOM"VTT_ABC_PWR_VR";
"A\NAC"15;
END.
